(kicad_pcb
	(version 20260206)
	(generator "pcbnew")
	(generator_version "10.0")
	(general
		(thickness 1.6)
		(legacy_teardrops no)
	)
	(paper "A4")
	(title_block
		(title "Wiwynn_Tioga_Pass_MB.brd")
		(comment 1 "Tioga Pass / footprints 3033-3040 of 4770")
	)
	(layers
		(0 "F.Cu" signal "TOP")
		(4 "In1.Cu" signal "L2GND")
		(6 "In2.Cu" signal "L3")
		(8 "In3.Cu" signal "L4GND")
		(10 "In4.Cu" signal "L5")
		(12 "In5.Cu" signal "L6GND")
		(14 "In6.Cu" signal "L7VCC")
		(16 "In7.Cu" signal "L8VCC")
		(18 "In8.Cu" signal "L9GND")
		(20 "In9.Cu" signal "L10")
		(22 "In10.Cu" signal "L11GND")
		(24 "In11.Cu" signal "L12")
		(26 "In12.Cu" signal "L13GND")
		(2 "B.Cu" signal "BOTTOM")
		(9 "F.Adhes" user "F.Adhesive")
		(11 "B.Adhes" user "B.Adhesive")
		(13 "F.Paste" user "Package Geometry/Pastemask Top")
		(15 "B.Paste" user "Package Geometry/Pastemask Bottom")
		(5 "F.SilkS" user "Ref Des/Silkscreen Top")
		(7 "B.SilkS" user "Ref Des/Silkscreen Bottom")
		(1 "F.Mask" user "Board Geometry/Soldermask Top")
		(3 "B.Mask" user "Board Geometry/Soldermask Bottom")
		(17 "Dwgs.User" user "User.Drawings")
		(19 "Cmts.User" user "User.Comments")
		(21 "Eco1.User" user "User.Eco1")
		(23 "Eco2.User" user "User.Eco2")
		(25 "Edge.Cuts" user "Board Geometry/Outline")
		(27 "Margin" user)
		(31 "F.CrtYd" user "Package Geometry/Place Bound Top")
		(29 "B.CrtYd" user "Package Geometry/Place Bound Bottom")
		(35 "F.Fab" user "Ref Des/Assembly Top")
		(33 "B.Fab" user "Ref Des/Assembly Bottom")
	)
	(footprint ""
		(layer "B.Cu")
		(at 253.392432 -135.4074 90)
		(property "Reference" "C5M4"
			(at -1.848866 0.752348 90)
			(unlocked yes)
			(layer "B.SilkS")
			(effects
				(font
					(size 1.27 0.9652)
					(thickness 0.1524)
				)
				(justify mirror)
			)
		)
		(property "Value" ""
			(at 0 0 90)
			(layer "B.Fab")
			(effects
				(font
					(size 1.27 1.27)
				)
				(justify mirror)
			)
		)
		(duplicate_pad_numbers_are_jumpers no)
		(fp_rect
			(start 0.500126 1.598422)
			(end -0.500126 -0.201422)
			(stroke
				(width 0)
				(type default)
			)
			(fill no)
			(layer "B.CrtYd")
		)
		(fp_line
			(start 0.500126 -0.201422)
			(end -0.500126 -0.201422)
			(stroke
				(width 0.1)
				(type default)
			)
			(layer "B.Fab")
		)
		(fp_line
			(start -0.500126 -0.201422)
			(end -0.500126 1.598422)
			(stroke
				(width 0.1)
				(type default)
			)
			(layer "B.Fab")
		)
		(fp_line
			(start 0.500126 1.598422)
			(end 0.500126 -0.201422)
			(stroke
				(width 0.1)
				(type default)
			)
			(layer "B.Fab")
		)
		(fp_line
			(start -0.500126 1.598422)
			(end 0.500126 1.598422)
			(stroke
				(width 0.1)
				(type default)
			)
			(layer "B.Fab")
		)
		(pad "1" smd rect
			(at 0 0)
			(size 0.889 0.9906)
			(layers "B.Cu" "B.Mask" "B.Paste")
			(net "PVDDQ_DEF")
		)
		(pad "2" smd rect
			(at 0 1.397)
			(size 0.889 0.9906)
			(layers "B.Cu" "B.Mask" "B.Paste")
			(net "GND")
		)
		(zone
			(layer "B.Cu")
			(hatch none 0.5)
			(connect_pads
				(clearance 0)
			)
			(min_thickness 0.25)
			(keepout
				(tracks not_allowed)
				(vias allowed)
				(pads allowed)
				(copperpour not_allowed)
				(footprints allowed)
			)
			(placement
				(enabled no)
				(sheetname "")
			)
			(fill
				(thermal_gap 0.5)
				(thermal_bridge_width 0.5)
				(island_removal_mode 0)
			)
			(polygon
				(pts
					(xy 254.344932 -135.9027) (xy 253.836932 -135.9027) (xy 253.836932 -134.9121) (xy 254.344932 -134.9121)
				)
			)
		)
		(zone
			(layer "B.Cu")
			(hatch none 0.5)
			(connect_pads
				(clearance 0)
			)
			(min_thickness 0.25)
			(keepout
				(tracks allowed)
				(vias not_allowed)
				(pads allowed)
				(copperpour not_allowed)
				(footprints allowed)
			)
			(placement
				(enabled no)
				(sheetname "")
			)
			(fill
				(thermal_gap 0.5)
				(thermal_bridge_width 0.5)
				(island_removal_mode 0)
			)
			(polygon
				(pts
					(xy 254.344932 -135.9027) (xy 253.836932 -135.9027) (xy 253.836932 -134.9121) (xy 254.344932 -134.9121)
				)
			)
		)
	)
	(footprint ""
		(layer "B.Cu")
		(at 253.392432 -12.954 90)
		(property "Reference" "C5G44"
			(at -1.14681 0.76708 180)
			(unlocked yes)
			(layer "B.SilkS")
			(effects
				(font
					(size 0.7874 0.5842)
					(thickness 0.1524)
				)
				(justify mirror)
			)
		)
		(property "Value" ""
			(at 0 0 90)
			(layer "B.Fab")
			(effects
				(font
					(size 1.27 1.27)
				)
				(justify mirror)
			)
		)
		(duplicate_pad_numbers_are_jumpers no)
		(fp_rect
			(start -0.4953 -0.2032)
			(end 0.4953 1.6002)
			(stroke
				(width 0)
				(type default)
			)
			(fill no)
			(layer "B.CrtYd")
		)
		(fp_line
			(start 0.4953 -0.2032)
			(end -0.4953 -0.2032)
			(stroke
				(width 0.1)
				(type default)
			)
			(layer "B.Fab")
		)
		(fp_line
			(start -0.4953 -0.2032)
			(end -0.4953 1.6002)
			(stroke
				(width 0.1)
				(type default)
			)
			(layer "B.Fab")
		)
		(fp_line
			(start 0.4953 1.6002)
			(end 0.4953 -0.2032)
			(stroke
				(width 0.1)
				(type default)
			)
			(layer "B.Fab")
		)
		(fp_line
			(start -0.4953 1.6002)
			(end 0.4953 1.6002)
			(stroke
				(width 0.1)
				(type default)
			)
			(layer "B.Fab")
		)
		(pad "1" smd rect
			(at 0 0 270)
			(size 0.762 0.889)
			(layers "B.Cu" "B.Mask" "B.Paste")
			(net "PVDDQ_ABC")
		)
		(pad "2" smd rect
			(at 0 1.397 270)
			(size 0.762 0.889)
			(layers "B.Cu" "B.Mask" "B.Paste")
			(net "GND")
		)
		(zone
			(layer "B.Cu")
			(hatch none 0.5)
			(connect_pads
				(clearance 0)
			)
			(min_thickness 0.25)
			(keepout
				(tracks not_allowed)
				(vias allowed)
				(pads allowed)
				(copperpour not_allowed)
				(footprints allowed)
			)
			(placement
				(enabled no)
				(sheetname "")
			)
			(fill
				(thermal_gap 0.5)
				(thermal_bridge_width 0.5)
				(island_removal_mode 0)
			)
			(polygon
				(pts
					(xy 253.836932 -12.573) (xy 254.344932 -12.573) (xy 254.344932 -13.335) (xy 253.836932 -13.335)
				)
			)
		)
	)
	(footprint ""
		(layer "B.Cu")
		(at 87.158068 -8.1534 -90)
		(property "Reference" "C8U5"
			(at -1.848866 0.752348 270)
			(unlocked yes)
			(layer "B.SilkS")
			(effects
				(font
					(size 1.27 0.9652)
					(thickness 0.1524)
				)
				(justify mirror)
			)
		)
		(property "Value" ""
			(at 0 0 90)
			(layer "B.Fab")
			(effects
				(font
					(size 1.27 1.27)
				)
				(justify mirror)
			)
		)
		(duplicate_pad_numbers_are_jumpers no)
		(fp_rect
			(start 0.500126 1.598422)
			(end -0.500126 -0.201422)
			(stroke
				(width 0)
				(type default)
			)
			(fill no)
			(layer "B.CrtYd")
		)
		(fp_line
			(start -0.500126 1.598422)
			(end 0.500126 1.598422)
			(stroke
				(width 0.1)
				(type default)
			)
			(layer "B.Fab")
		)
		(fp_line
			(start 0.500126 1.598422)
			(end 0.500126 -0.201422)
			(stroke
				(width 0.1)
				(type default)
			)
			(layer "B.Fab")
		)
		(fp_line
			(start -0.500126 -0.201422)
			(end -0.500126 1.598422)
			(stroke
				(width 0.1)
				(type default)
			)
			(layer "B.Fab")
		)
		(fp_line
			(start 0.500126 -0.201422)
			(end -0.500126 -0.201422)
			(stroke
				(width 0.1)
				(type default)
			)
			(layer "B.Fab")
		)
		(pad "1" smd rect
			(at 0 0 180)
			(size 0.889 0.9906)
			(layers "B.Cu" "B.Mask" "B.Paste")
			(net "PVDDQ_GHJ")
		)
		(pad "2" smd rect
			(at 0 1.397 180)
			(size 0.889 0.9906)
			(layers "B.Cu" "B.Mask" "B.Paste")
			(net "GND")
		)
		(zone
			(layer "B.Cu")
			(hatch none 0.5)
			(connect_pads
				(clearance 0)
			)
			(min_thickness 0.25)
			(keepout
				(tracks not_allowed)
				(vias allowed)
				(pads allowed)
				(copperpour not_allowed)
				(footprints allowed)
			)
			(placement
				(enabled no)
				(sheetname "")
			)
			(fill
				(thermal_gap 0.5)
				(thermal_bridge_width 0.5)
				(island_removal_mode 0)
			)
			(polygon
				(pts
					(xy 86.205568 -7.6581) (xy 86.713568 -7.6581) (xy 86.713568 -8.6487) (xy 86.205568 -8.6487)
				)
			)
		)
		(zone
			(layer "B.Cu")
			(hatch none 0.5)
			(connect_pads
				(clearance 0)
			)
			(min_thickness 0.25)
			(keepout
				(tracks allowed)
				(vias not_allowed)
				(pads allowed)
				(copperpour not_allowed)
				(footprints allowed)
			)
			(placement
				(enabled no)
				(sheetname "")
			)
			(fill
				(thermal_gap 0.5)
				(thermal_bridge_width 0.5)
				(island_removal_mode 0)
			)
			(polygon
				(pts
					(xy 86.205568 -7.6581) (xy 86.713568 -7.6581) (xy 86.713568 -8.6487) (xy 86.205568 -8.6487)
				)
			)
		)
	)
	(footprint ""
		(layer "B.Cu")
		(at 457.454 -4.2164 90)
		(property "Reference" "R1U50"
			(at 0 0 90)
			(layer "B.SilkS")
			(hide yes)
			(effects
				(font
					(size 1.27 1.27)
				)
				(justify mirror)
			)
		)
		(property "Value" ""
			(at 0 0 90)
			(layer "B.Fab")
			(effects
				(font
					(size 1.27 1.27)
				)
				(justify mirror)
			)
		)
		(duplicate_pad_numbers_are_jumpers no)
		(fp_poly
			(pts
				(xy 0.2794 -0.1016) (xy -0.2794 -0.1016) (xy -0.2794 0.9906) (xy 0.2794 0.9906)
			)
			(stroke
				(width 0)
				(type default)
			)
			(fill no)
			(layer "B.CrtYd")
		)
		(fp_line
			(start 0.2794 -0.1016)
			(end 0.2794 0.9906)
			(stroke
				(width 0.1)
				(type default)
			)
			(layer "B.Fab")
		)
		(fp_line
			(start -0.2794 -0.1016)
			(end 0.2794 -0.1016)
			(stroke
				(width 0.1)
				(type default)
			)
			(layer "B.Fab")
		)
		(fp_line
			(start 0.2794 0.9906)
			(end -0.2794 0.9906)
			(stroke
				(width 0.1)
				(type default)
			)
			(layer "B.Fab")
		)
		(fp_line
			(start -0.2794 0.9906)
			(end -0.2794 -0.1016)
			(stroke
				(width 0.1)
				(type default)
			)
			(layer "B.Fab")
		)
		(pad "1" smd rect
			(at 0 0 270)
			(size 0.508 0.508)
			(layers "B.Cu" "B.Mask" "B.Paste")
			(net "A_P3V_BAT_R")
		)
		(pad "2" smd rect
			(at 0 0.889 270)
			(size 0.508 0.508)
			(layers "B.Cu" "B.Mask" "B.Paste")
			(net "P3V_BAT_SOURCE_R")
		)
		(zone
			(layer "B.Cu")
			(hatch none 0.5)
			(connect_pads
				(clearance 0)
			)
			(min_thickness 0.25)
			(keepout
				(tracks allowed)
				(vias not_allowed)
				(pads allowed)
				(copperpour not_allowed)
				(footprints allowed)
			)
			(placement
				(enabled no)
				(sheetname "")
			)
			(fill
				(thermal_gap 0.5)
				(thermal_bridge_width 0.5)
				(island_removal_mode 0)
			)
			(polygon
				(pts
					(xy 457.708 -4.4704) (xy 457.708 -3.9624) (xy 458.089 -3.9624) (xy 458.089 -4.4704)
				)
			)
		)
		(zone
			(layer "B.Cu")
			(hatch none 0.5)
			(connect_pads
				(clearance 0)
			)
			(min_thickness 0.25)
			(keepout
				(tracks not_allowed)
				(vias allowed)
				(pads allowed)
				(copperpour not_allowed)
				(footprints allowed)
			)
			(placement
				(enabled no)
				(sheetname "")
			)
			(fill
				(thermal_gap 0.5)
				(thermal_bridge_width 0.5)
				(island_removal_mode 0)
			)
			(polygon
				(pts
					(xy 458.089 -4.4704) (xy 458.089 -3.9624) (xy 457.708 -3.9624) (xy 457.708 -4.4704)
				)
			)
		)
	)
	(footprint ""
		(layer "B.Cu")
		(at 453.517 -116.49202)
		(property "Reference" "C1M14"
			(at 0 0 0)
			(layer "B.SilkS")
			(hide yes)
			(effects
				(font
					(size 1.27 1.27)
				)
				(justify mirror)
			)
		)
		(property "Value" ""
			(at 0 0 0)
			(layer "B.Fab")
			(effects
				(font
					(size 1.27 1.27)
				)
				(justify mirror)
			)
		)
		(duplicate_pad_numbers_are_jumpers no)
		(fp_rect
			(start -0.3048 0.9906)
			(end 0.3048 -0.1016)
			(stroke
				(width 0)
				(type default)
			)
			(fill no)
			(layer "B.CrtYd")
		)
		(fp_line
			(start -0.3048 -0.1016)
			(end 0.3048 -0.1016)
			(stroke
				(width 0.1)
				(type default)
			)
			(layer "B.Fab")
		)
		(fp_line
			(start -0.3048 0.9906)
			(end -0.3048 -0.1016)
			(stroke
				(width 0.1)
				(type default)
			)
			(layer "B.Fab")
		)
		(fp_line
			(start 0.3048 -0.1016)
			(end 0.3048 0.9906)
			(stroke
				(width 0.1)
				(type default)
			)
			(layer "B.Fab")
		)
		(fp_line
			(start 0.3048 0.9906)
			(end -0.3048 0.9906)
			(stroke
				(width 0.1)
				(type default)
			)
			(layer "B.Fab")
		)
		(pad "1" smd rect
			(at 0 0 180)
			(size 0.508 0.508)
			(layers "B.Cu" "B.Mask" "B.Paste")
			(net "P3E_CPU0_PE3_OCP_TXP<11>")
		)
		(pad "2" smd rect
			(at 0 0.889 180)
			(size 0.508 0.508)
			(layers "B.Cu" "B.Mask" "B.Paste")
			(net "P3E_OCP_CPU0_PE3_C_TXP<11>")
		)
		(zone
			(layer "B.Cu")
			(hatch none 0.5)
			(connect_pads
				(clearance 0)
			)
			(min_thickness 0.25)
			(keepout
				(tracks allowed)
				(vias not_allowed)
				(pads allowed)
				(copperpour not_allowed)
				(footprints allowed)
			)
			(placement
				(enabled no)
				(sheetname "")
			)
			(fill
				(thermal_gap 0.5)
				(thermal_bridge_width 0.5)
				(island_removal_mode 0)
			)
			(polygon
				(pts
					(xy 453.263 -115.85702) (xy 453.771 -115.85702) (xy 453.771 -116.23802) (xy 453.263 -116.23802)
				)
			)
		)
		(zone
			(layer "B.Cu")
			(hatch none 0.5)
			(connect_pads
				(clearance 0)
			)
			(min_thickness 0.25)
			(keepout
				(tracks not_allowed)
				(vias allowed)
				(pads allowed)
				(copperpour not_allowed)
				(footprints allowed)
			)
			(placement
				(enabled no)
				(sheetname "")
			)
			(fill
				(thermal_gap 0.5)
				(thermal_bridge_width 0.5)
				(island_removal_mode 0)
			)
			(polygon
				(pts
					(xy 453.263 -115.85702) (xy 453.771 -115.85702) (xy 453.771 -116.23802) (xy 453.263 -116.23802)
				)
			)
		)
	)
	(footprint ""
		(layer "B.Cu")
		(at -2.5146 -127.7112 -90)
		(property "Reference" "R9M7"
			(at 0 0 90)
			(layer "B.SilkS")
			(hide yes)
			(effects
				(font
					(size 1.27 1.27)
				)
				(justify mirror)
			)
		)
		(property "Value" ""
			(at 0 0 90)
			(layer "B.Fab")
			(effects
				(font
					(size 1.27 1.27)
				)
				(justify mirror)
			)
		)
		(duplicate_pad_numbers_are_jumpers no)
		(fp_rect
			(start 0.2794 0.9906)
			(end -0.2794 -0.1016)
			(stroke
				(width 0)
				(type default)
			)
			(fill no)
			(layer "B.CrtYd")
		)
		(fp_line
			(start -0.2794 0.9906)
			(end -0.2794 -0.1016)
			(stroke
				(width 0.1)
				(type default)
			)
			(layer "B.Fab")
		)
		(fp_line
			(start 0.2794 0.9906)
			(end -0.2794 0.9906)
			(stroke
				(width 0.1)
				(type default)
			)
			(layer "B.Fab")
		)
		(fp_line
			(start -0.2794 -0.1016)
			(end 0.2794 -0.1016)
			(stroke
				(width 0.1)
				(type default)
			)
			(layer "B.Fab")
		)
		(fp_line
			(start 0.2794 -0.1016)
			(end 0.2794 0.9906)
			(stroke
				(width 0.1)
				(type default)
			)
			(layer "B.Fab")
		)
		(pad "1" smd rect
			(at 0 0 90)
			(size 0.508 0.508)
			(layers "B.Cu" "B.Mask" "B.Paste")
			(net "PVCCIO_CPU1")
		)
		(pad "2" smd rect
			(at 0 0.889 90)
			(size 0.508 0.508)
			(layers "B.Cu" "B.Mask" "B.Paste")
			(net "SVID_DIO1_CPU1_R")
		)
		(zone
			(layer "B.Cu")
			(hatch none 0.5)
			(connect_pads
				(clearance 0)
			)
			(min_thickness 0.25)
			(keepout
				(tracks not_allowed)
				(vias allowed)
				(pads allowed)
				(copperpour not_allowed)
				(footprints allowed)
			)
			(placement
				(enabled no)
				(sheetname "")
			)
			(fill
				(thermal_gap 0.5)
				(thermal_bridge_width 0.5)
				(island_removal_mode 0)
			)
			(polygon
				(pts
					(xy -3.1496 -127.4572) (xy -2.7686 -127.4572) (xy -2.7686 -127.9652) (xy -3.1496 -127.9652)
				)
			)
		)
		(zone
			(layer "B.Cu")
			(hatch none 0.5)
			(connect_pads
				(clearance 0)
			)
			(min_thickness 0.25)
			(keepout
				(tracks allowed)
				(vias not_allowed)
				(pads allowed)
				(copperpour not_allowed)
				(footprints allowed)
			)
			(placement
				(enabled no)
				(sheetname "")
			)
			(fill
				(thermal_gap 0.5)
				(thermal_bridge_width 0.5)
				(island_removal_mode 0)
			)
			(polygon
				(pts
					(xy -3.1496 -127.4572) (xy -2.7686 -127.4572) (xy -2.7686 -127.9652) (xy -3.1496 -127.9652)
				)
			)
		)
	)
	(footprint ""
		(layer "B.Cu")
		(at 32.832802 -56.646064 90)
		(property "Reference" "C9R11"
			(at 0 0 90)
			(layer "B.SilkS")
			(hide yes)
			(effects
				(font
					(size 1.27 1.27)
				)
				(justify mirror)
			)
		)
		(property "Value" ""
			(at 0 0 90)
			(layer "B.Fab")
			(effects
				(font
					(size 1.27 1.27)
				)
				(justify mirror)
			)
		)
		(duplicate_pad_numbers_are_jumpers no)
		(fp_poly
			(pts
				(xy 0.7239 -0.2159) (xy -0.7239 -0.2159) (xy -0.7239 1.9939) (xy 0.7239 1.9939)
			)
			(stroke
				(width 0)
				(type default)
			)
			(fill no)
			(layer "B.CrtYd")
		)
		(fp_line
			(start 0.7239 -0.2159)
			(end 0.7239 1.9939)
			(stroke
				(width 0.1)
				(type default)
			)
			(layer "B.Fab")
		)
		(fp_line
			(start -0.7239 -0.2159)
			(end 0.7239 -0.2159)
			(stroke
				(width 0.1)
				(type default)
			)
			(layer "B.Fab")
		)
		(fp_line
			(start 0.7239 1.9939)
			(end -0.7239 1.9939)
			(stroke
				(width 0.1)
				(type default)
			)
			(layer "B.Fab")
		)
		(fp_line
			(start -0.7239 1.9939)
			(end -0.7239 -0.2159)
			(stroke
				(width 0.1)
				(type default)
			)
			(layer "B.Fab")
		)
		(pad "1" smd rect
			(at 0 0 270)
			(size 1.27 1.016)
			(layers "B.Cu" "B.Mask" "B.Paste")
			(net "VR_FET_SW_P12V_STBY_PVCCIN_CPU1")
		)
		(pad "2" smd rect
			(at 0 1.778 270)
			(size 1.27 1.016)
			(layers "B.Cu" "B.Mask" "B.Paste")
			(net "GND")
		)
		(zone
			(layer "B.Cu")
			(hatch none 0.5)
			(connect_pads
				(clearance 0)
			)
			(min_thickness 0.25)
			(keepout
				(tracks not_allowed)
				(vias allowed)
				(pads allowed)
				(copperpour not_allowed)
				(footprints allowed)
			)
			(placement
				(enabled no)
				(sheetname "")
			)
			(fill
				(thermal_gap 0.5)
				(thermal_bridge_width 0.5)
				(island_removal_mode 0)
			)
			(polygon
				(pts
					(xy 33.340802 -57.281064) (xy 33.340802 -56.011064) (xy 34.102802 -56.011064) (xy 34.102802 -57.281064)
				)
			)
		)
	)
	(footprint ""
		(layer "B.Cu")
		(at 15.77848 -75.35672 90)
		(property "Reference" "R9P24"
			(at 0 0 90)
			(layer "B.SilkS")
			(hide yes)
			(effects
				(font
					(size 1.27 1.27)
				)
				(justify mirror)
			)
		)
		(property "Value" ""
			(at 0 0 90)
			(layer "B.Fab")
			(effects
				(font
					(size 1.27 1.27)
				)
				(justify mirror)
			)
		)
		(duplicate_pad_numbers_are_jumpers no)
		(fp_rect
			(start -0.2794 -0.1016)
			(end 0.2794 0.9906)
			(stroke
				(width 0)
				(type default)
			)
			(fill no)
			(layer "B.CrtYd")
		)
		(fp_line
			(start 0.2794 -0.1016)
			(end 0.2794 0.9906)
			(stroke
				(width 0.1)
				(type default)
			)
			(layer "B.Fab")
		)
		(fp_line
			(start -0.2794 -0.1016)
			(end 0.2794 -0.1016)
			(stroke
				(width 0.1)
				(type default)
			)
			(layer "B.Fab")
		)
		(fp_line
			(start 0.2794 0.9906)
			(end -0.2794 0.9906)
			(stroke
				(width 0.1)
				(type default)
			)
			(layer "B.Fab")
		)
		(fp_line
			(start -0.2794 0.9906)
			(end -0.2794 -0.1016)
			(stroke
				(width 0.1)
				(type default)
			)
			(layer "B.Fab")
		)
		(pad "1" smd rect
			(at 0 0 270)
			(size 0.508 0.508)
			(layers "B.Cu" "B.Mask" "B.Paste")
			(net "A_HSC_PWGIN")
		)
		(pad "2" smd rect
			(at 0 0.889 270)
			(size 0.508 0.508)
			(layers "B.Cu" "B.Mask" "B.Paste")
			(net "AGND_HSC")
		)
		(zone
			(layer "B.Cu")
			(hatch none 0.5)
			(connect_pads
				(clearance 0)
			)
			(min_thickness 0.25)
			(keepout
				(tracks allowed)
				(vias not_allowed)
				(pads allowed)
				(copperpour not_allowed)
				(footprints allowed)
			)
			(placement
				(enabled no)
				(sheetname "")
			)
			(fill
				(thermal_gap 0.5)
				(thermal_bridge_width 0.5)
				(island_removal_mode 0)
			)
			(polygon
				(pts
					(xy 16.03248 -75.10272) (xy 16.41348 -75.10272) (xy 16.41348 -75.61072) (xy 16.03248 -75.61072)
				)
			)
		)
		(zone
			(layer "B.Cu")
			(hatch none 0.5)
			(connect_pads
				(clearance 0)
			)
			(min_thickness 0.25)
			(keepout
				(tracks not_allowed)
				(vias allowed)
				(pads allowed)
				(copperpour not_allowed)
				(footprints allowed)
			)
			(placement
				(enabled no)
				(sheetname "")
			)
			(fill
				(thermal_gap 0.5)
				(thermal_bridge_width 0.5)
				(island_removal_mode 0)
			)
			(polygon
				(pts
					(xy 16.03248 -75.10272) (xy 16.41348 -75.10272) (xy 16.41348 -75.61072) (xy 16.03248 -75.61072)
				)
			)
		)
	)
)
